# T6G (Grand Teton) — schematic netlist excerpt (pin names and nets, part order shuffled) for the footprints in the layout excerpt that follows; sources: Cadence DE-HDL packaged netlist, KiCad conversion of 04192023_DAF0TMB3IC0_F0TG_MB_C_brd_V02_OCP.brd

R2356  Q_RES  10K 1% CHIP  pkg 0402LF  page 189 : A = P5V_AUX_VCC ; B = PWRGD_P5V_AUX_R
C462  Q_CAP  0.1UF 10V 10% X7S  pkg C0201  page 356 : A = P0V9_CPU1_RT3_2A ; B = GND
C7024  Q_CAPP  470UF 2.5V 20% SPCAP  pkg SMLF  page 334 : A = P0V9_CPU1_RT1_2A ; B = GND

(kicad_pcb
	(version 20260206)
	(generator "pcbnew")
	(generator_version "10.0")
	(general
		(thickness 1.6)
		(legacy_teardrops no)
	)
	(paper "A4")
	(title_block
		(title "04192023_DAF0TMB3IC0_F0TG_MB_C_brd_V02_OCP.brd")
		(comment 1 "Grand Teton / footprints 7770-7772 of 8354")
	)
	(layers
		(0 "F.Cu" signal "TOP")
		(4 "In1.Cu" signal "GND")
		(6 "In2.Cu" signal "IN1")
		(8 "In3.Cu" signal "GND1")
		(10 "In4.Cu" signal "IN2")
		(12 "In5.Cu" signal "GND2")
		(14 "In6.Cu" signal "IN3")
		(16 "In7.Cu" signal "GND3")
		(18 "In8.Cu" signal "VCC")
		(20 "In9.Cu" signal "VCC1")
		(22 "In10.Cu" signal "GND4")
		(24 "In11.Cu" signal "IN4")
		(26 "In12.Cu" signal "GND5")
		(28 "In13.Cu" signal "IN5")
		(30 "In14.Cu" signal "GND6")
		(32 "In15.Cu" signal "IN6")
		(34 "In16.Cu" signal "GND7")
		(2 "B.Cu" signal "BOTTOM")
		(9 "F.Adhes" user "F.Adhesive")
		(11 "B.Adhes" user "B.Adhesive")
		(13 "F.Paste" user "Package Geometry/Pastemask Top")
		(15 "B.Paste" user "Package Geometry/Pastemask Bottom")
		(5 "F.SilkS" user "Ref Des/Silkscreen Top")
		(7 "B.SilkS" user "Ref Des/Silkscreen Bottom")
		(1 "F.Mask" user "Board Geometry/Soldermask Top")
		(3 "B.Mask" user "Board Geometry/Soldermask Bottom")
		(17 "Dwgs.User" user "User.Drawings")
		(19 "Cmts.User" user "User.Comments")
		(21 "Eco1.User" user "User.Eco1")
		(23 "Eco2.User" user "User.Eco2")
		(25 "Edge.Cuts" user "Board Geometry/Outline")
		(27 "Margin" user)
		(31 "F.CrtYd" user "Package Geometry/Place Bound Top")
		(29 "B.CrtYd" user "Package Geometry/Place Bound Bottom")
		(35 "F.Fab" user "Ref Des/Assembly Top")
		(33 "B.Fab" user "Ref Des/Assembly Bottom")
	)
	(footprint ""
		(layer "B.Cu")
		(at 131.418584 -388.011162 -90)
		(property "Reference" "C462"
			(at 0 0 90)
			(layer "B.SilkS")
			(hide yes)
			(effects
				(font
					(size 1.27 1.27)
				)
				(justify mirror)
			)
		)
		(property "Value" ""
			(at 0 0 90)
			(layer "B.Fab")
			(effects
				(font
					(size 1.27 1.27)
				)
				(justify mirror)
			)
		)
		(duplicate_pad_numbers_are_jumpers no)
		(fp_line
			(start -0.299974 0.150114)
			(end 0.299974 0.150114)
			(stroke
				(width 0.1)
				(type default)
			)
			(layer "B.Fab")
		)
		(fp_line
			(start 0.299974 0.150114)
			(end 0.299974 -0.150114)
			(stroke
				(width 0.1)
				(type default)
			)
			(layer "B.Fab")
		)
		(fp_line
			(start -0.299974 -0.150114)
			(end -0.299974 0.150114)
			(stroke
				(width 0.1)
				(type default)
			)
			(layer "B.Fab")
		)
		(fp_line
			(start 0.299974 -0.150114)
			(end -0.299974 -0.150114)
			(stroke
				(width 0.1)
				(type default)
			)
			(layer "B.Fab")
		)
		(pad "1" smd rect
			(at 0.2667 0 90)
			(size 0.3048 0.381)
			(layers "B.Cu" "B.Mask" "B.Paste")
			(net "P0V9_CPU1_RT3_2A")
		)
		(pad "2" smd rect
			(at -0.2667 0 90)
			(size 0.3048 0.381)
			(layers "B.Cu" "B.Mask" "B.Paste")
			(net "GND")
		)
	)
	(footprint ""
		(layer "B.Cu")
		(at 411.576266 -139.42949 90)
		(property "Reference" "R2356"
			(at 0 0 90)
			(layer "B.SilkS")
			(hide yes)
			(effects
				(font
					(size 1.27 1.27)
				)
				(justify mirror)
			)
		)
		(property "Value" ""
			(at 0 0 90)
			(layer "B.Fab")
			(effects
				(font
					(size 1.27 1.27)
				)
				(justify mirror)
			)
		)
		(duplicate_pad_numbers_are_jumpers no)
		(fp_line
			(start 0.7874 -0.4064)
			(end -0.7874 -0.4064)
			(stroke
				(width 0.1524)
				(type default)
			)
			(layer "B.SilkS")
		)
		(fp_line
			(start -0.7874 -0.4064)
			(end -0.7874 0.4064)
			(stroke
				(width 0.1524)
				(type default)
			)
			(layer "B.SilkS")
		)
		(fp_line
			(start 0.7874 0.4064)
			(end 0.7874 -0.4064)
			(stroke
				(width 0.1524)
				(type default)
			)
			(layer "B.SilkS")
		)
		(fp_line
			(start -0.7874 0.4064)
			(end 0.7874 0.4064)
			(stroke
				(width 0.1524)
				(type default)
			)
			(layer "B.SilkS")
		)
		(fp_line
			(start 0.67945 -0.305054)
			(end 0.12065 -0.305054)
			(stroke
				(width 0.1)
				(type default)
			)
			(layer "B.Fab")
		)
		(fp_line
			(start 0.12065 -0.305054)
			(end 0.12065 -0.2794)
			(stroke
				(width 0.1)
				(type default)
			)
			(layer "B.Fab")
		)
		(fp_line
			(start -0.12065 -0.3048)
			(end -0.67945 -0.3048)
			(stroke
				(width 0.1)
				(type default)
			)
			(layer "B.Fab")
		)
		(fp_line
			(start -0.67945 -0.3048)
			(end -0.67945 0.3048)
			(stroke
				(width 0.1)
				(type default)
			)
			(layer "B.Fab")
		)
		(fp_line
			(start 0.12065 -0.2794)
			(end -0.12065 -0.2794)
			(stroke
				(width 0.1)
				(type default)
			)
			(layer "B.Fab")
		)
		(fp_line
			(start -0.12065 -0.2794)
			(end -0.12065 -0.3048)
			(stroke
				(width 0.1)
				(type default)
			)
			(layer "B.Fab")
		)
		(fp_line
			(start 0.12065 0.2794)
			(end 0.12065 0.3048)
			(stroke
				(width 0.1)
				(type default)
			)
			(layer "B.Fab")
		)
		(fp_line
			(start -0.120396 0.2794)
			(end 0.12065 0.2794)
			(stroke
				(width 0.1)
				(type default)
			)
			(layer "B.Fab")
		)
		(fp_line
			(start 0.67945 0.3048)
			(end 0.67945 -0.305054)
			(stroke
				(width 0.1)
				(type default)
			)
			(layer "B.Fab")
		)
		(fp_line
			(start 0.12065 0.3048)
			(end 0.67945 0.3048)
			(stroke
				(width 0.1)
				(type default)
			)
			(layer "B.Fab")
		)
		(fp_line
			(start -0.120396 0.3048)
			(end -0.120396 0.2794)
			(stroke
				(width 0.1)
				(type default)
			)
			(layer "B.Fab")
		)
		(fp_line
			(start -0.67945 0.3048)
			(end -0.120396 0.3048)
			(stroke
				(width 0.1)
				(type default)
			)
			(layer "B.Fab")
		)
		(pad "1" smd circle
			(at 0.40005 0 270)
			(size 0 0)
			(layers "B.Cu" "B.Mask" "B.Paste")
			(net "P5V_AUX_VCC")
		)
		(pad "2" smd circle
			(at -0.40005 0 270)
			(size 0 0)
			(layers "B.Cu" "B.Mask" "B.Paste")
			(net "PWRGD_P5V_AUX_R")
		)
	)
	(footprint ""
		(layer "B.Cu")
		(at 85.024976 -381.11303 180)
		(property "Reference" "C7024"
			(at -1.773428 -2.989072 0)
			(unlocked yes)
			(layer "B.SilkS")
			(effects
				(font
					(size 0.7874 0.5842)
					(thickness 0.1524)
				)
				(justify left mirror)
			)
		)
		(property "Value" ""
			(at 0 0 0)
			(layer "B.Fab")
			(effects
				(font
					(size 1.27 1.27)
				)
				(justify mirror)
			)
		)
		(duplicate_pad_numbers_are_jumpers no)
		(fp_line
			(start 4.84378 -2.150618)
			(end 4.842256 2.163064)
			(stroke
				(width 0.1524)
				(type default)
			)
			(layer "B.SilkS")
		)
		(fp_line
			(start 4.84378 -2.150618)
			(end 4.53898 -2.150618)
			(stroke
				(width 0.1524)
				(type default)
			)
			(layer "B.SilkS")
		)
		(fp_line
			(start 4.83108 2.150364)
			(end 4.447794 2.149348)
			(stroke
				(width 0.1524)
				(type default)
			)
			(layer "B.SilkS")
		)
		(fp_line
			(start 4.69138 -2.150618)
			(end 4.692396 2.161032)
			(stroke
				(width 0.1524)
				(type default)
			)
			(layer "B.SilkS")
		)
		(fp_line
			(start 4.53898 2.15011)
			(end 4.53898 -2.15011)
			(stroke
				(width 0.1524)
				(type default)
			)
			(layer "B.SilkS")
		)
		(fp_line
			(start 4.53898 -2.15011)
			(end -4.53898 -2.15011)
			(stroke
				(width 0.1524)
				(type default)
			)
			(layer "B.SilkS")
		)
		(fp_line
			(start 4.53898 -2.150618)
			(end 4.539742 2.152142)
			(stroke
				(width 0.1524)
				(type default)
			)
			(layer "B.SilkS")
		)
		(fp_line
			(start -4.53898 2.15011)
			(end 4.53898 2.15011)
			(stroke
				(width 0.1524)
				(type default)
			)
			(layer "B.SilkS")
		)
		(fp_line
			(start -4.53898 -2.15011)
			(end -4.53898 2.15011)
			(stroke
				(width 0.1524)
				(type default)
			)
			(layer "B.SilkS")
		)
		(fp_line
			(start 3.64998 2.15011)
			(end 3.64998 -2.15011)
			(stroke
				(width 0.1)
				(type default)
			)
			(layer "B.Fab")
		)
		(fp_line
			(start 3.64998 -2.15011)
			(end -3.64998 -2.15011)
			(stroke
				(width 0.1)
				(type default)
			)
			(layer "B.Fab")
		)
		(fp_line
			(start -3.64998 2.15011)
			(end 3.64998 2.15011)
			(stroke
				(width 0.1)
				(type default)
			)
			(layer "B.Fab")
		)
		(fp_line
			(start -3.64998 -2.15011)
			(end -3.64998 2.15011)
			(stroke
				(width 0.1)
				(type default)
			)
			(layer "B.Fab")
		)
		(fp_text user "+"
			(at 4.256532 -3.098038 180)
			(unlocked yes)
			(layer "B.SilkS")
			(effects
				(font
					(size 1.905 1.4224)
					(thickness 0.1524)
				)
				(justify left mirror)
			)
		)
		(fp_text user "-"
			(at -2.946654 -2.901188 180)
			(unlocked yes)
			(layer "B.SilkS")
			(effects
				(font
					(size 1.905 1.4224)
					(thickness 0.1524)
				)
				(justify left mirror)
			)
		)
		(fp_text user "+"
			(at 6.214872 -0.337058 180)
			(unlocked yes)
			(layer "B.Fab")
			(effects
				(font
					(size 1.905 1.4224)
					(thickness 0.1524)
				)
				(justify left mirror)
			)
		)
		(fp_text user "-"
			(at -4.313174 -0.094488 180)
			(unlocked yes)
			(layer "B.Fab")
			(effects
				(font
					(size 1.905 1.4224)
					(thickness 0.1524)
				)
				(justify left mirror)
			)
		)
		(pad "1" smd rect
			(at 3.199892 0)
			(size 2.413 2.8194)
			(layers "B.Cu" "B.Mask" "B.Paste")
			(net "P0V9_CPU1_RT1_2A")
		)
		(pad "2" smd rect
			(at -3.199892 0)
			(size 2.413 2.8194)
			(layers "B.Cu" "B.Mask" "B.Paste")
			(net "GND")
		)
	)
)
